FILE_TYPE = MACRO_DRAWING;
SET COLOR_WIRE YELLOW;
SET COLOR_PROP MONO;
SET COLOR_DOT WHITE;
SET COLOR_ARC YELLOW;
SET COLOR_BODY GREEN;
SET COLOR_NOTE MONO;
SET PROP_DISPLAY VALUE;
SET PAGE_NUMBER P8;
FORCEADD INTEL_CORP_BPAGE..1
(14550 100);
FORCEPROP 1 LAST CUSTOM_TXT_CDS <CURRENT_DESIGN_SHEET> OF <TOTAL_DESIGN_SHEETS>
J 0
(14050 125);
PAINT GREEN (14050 125);
FORCEPROP 1 LAST CUSTOM_TXT_CDS <CON_LAST_MODIFIED>
J 0
(12625 450);
PAINT GREEN (12625 450);
FORCEPROP 2 LAST CUSTOM_TXT_CDS <XR_PAGE_TITLE>
J 0
(6660 5350);
DISPLAY 0.638298 (6660 5350);
PAINT PINK (6660 5350);
DISPLAY INVISIBLE (6660 5350);
FORCEPROP 1 LAST SCH_NUMBER H4694802
J 0
(13250 250);
DISPLAY 1.212766 (13250 250);
PAINT YELLOW (13250 250);
FORCEPROP 1 LAST SCH_DEPT BESD
J 1
(10100 200);
DISPLAY 1.212766 (10100 200);
PAINT YELLOW (10100 200);
FORCEPROP 1 LAST SCH_REV 2.420
J 0
(14300 250);
DISPLAY 0.978723 (14300 250);
PAINT YELLOW (14300 250);
FORCEPROP 1 LAST SCH_TITLE SMBUS BLOCK DIAGRAM
J 0
(6600 150);
DISPLAY 1.212766 (6600 150);
PAINT ORANGE (6600 150);
FORCEPROP 1 LAST SCH_ADDRESS1 2200 Mission College Blvd.
J 0
(10575 225);
DISPLAY 0.617021 (10575 225);
PAINT GREEN (10575 225);
FORCEPROP 1 LAST SCH_ADDRESS2 P.O. BOX 58119
J 0
(10575 175);
DISPLAY 0.617021 (10575 175);
PAINT GREEN (10575 175);
FORCEPROP 1 LAST SCH_ADDRESS3 Santa Clara, CA 95052-8119
J 0
(10575 125);
DISPLAY 0.617021 (10575 125);
PAINT GREEN (10575 125);
FORCEPROP 1 LAST COMMENT_BODY TRUE
J 0
(14562 112);
DISPLAY 0.468085 (14562 112);
PAINT GREEN (14562 112);
DISPLAY INVISIBLE (14562 112);
FORCEPROP 2 LAST PAGE_BORDER TRUE
J 0
(6660 5350);
DISPLAY 0.638298 (6660 5350);
PAINT PINK (6660 5350);
DISPLAY INVISIBLE (6660 5350);
FORCEPROP 2 LAST CDS_LIB mstr_symbols
J 0
(14550 100);
PAINT MONO (14550 100);
DISPLAY INVISIBLE (14550 100);
FORCEPROP 1 LAST CDS_CON_LAST_MODIFIED Tue Dec 01 11:47:57 2015
J 0
(13125 425);
PAINT ORANGE (13125 425);
DISPLAY INVISIBLE (13125 425);
FORCEPROP 2 LAST CDS_XR_PAGE_TITLE CR-8 : @BASEBOARD_FAB2_LIB.BASEBOARD_FAB2(SCH_1):PAGE8
J 0
(6660 5350);
DISPLAY 0.638298 (6660 5350);
PAINT PINK (6660 5350);
DISPLAY INVISIBLE (6660 5350);
FORCENOTE
$CDS_IMAGE|08_TiogaPass_SYSTEM_Block_diagram_1109.jpg|5250|4750
(10125 2800) 0;
DISPLAY CENTER (10125 2800);
PAINT MONO (10125 2800);
QUIT
